# S9S_MB_2U (Grand Teton) — schematic netlist excerpt (pin names and nets, part order shuffled) for the footprints in the layout excerpt that follows; sources: Cadence DE-HDL packaged netlist, KiCad conversion of 03242023_DA0F0TMBIJ0_F0T_Motherboard_J_brd_V01_OCP.brd

R3437  Q_RES  4.7K 5% CHIP  pkg 0402LF  page 147 : A = P3V3_AUX ; B = GPU_FPGA_OVERT_ISO_N
C812  Q_CAP_DIFFBUS  DIFF BUS_0.22UF 6.3V 20% X6S  pkg C0201  page 175 : \1\ = P5E_CPU1_PE1_TX_C_DN<12> ; \2\ = P5E_CPU1_PE1_TX_DN<12>
R4561  Q_RES  4.7K 5% CHIP  pkg 0402LF  page 146 : A = P3V3_AUX ; B = SWB_HSC_PWRGD_ISO

(kicad_pcb
	(version 20260206)
	(generator "pcbnew")
	(generator_version "10.0")
	(general
		(thickness 1.6)
		(legacy_teardrops no)
	)
	(paper "A4")
	(title_block
		(title "03242023_DA0F0TMBIJ0_F0T_Motherboard_J_brd_V01_OCP.brd")
		(comment 1 "Grand Teton / footprints 574-576 of 6105")
	)
	(layers
		(0 "F.Cu" signal "TOP")
		(4 "In1.Cu" signal "GND")
		(6 "In2.Cu" signal "IN1")
		(8 "In3.Cu" signal "GND1")
		(10 "In4.Cu" signal "IN2")
		(12 "In5.Cu" signal "GND2")
		(14 "In6.Cu" signal "IN3")
		(16 "In7.Cu" signal "GND3")
		(18 "In8.Cu" signal "VCC")
		(20 "In9.Cu" signal "VCC1")
		(22 "In10.Cu" signal "GND4")
		(24 "In11.Cu" signal "IN4")
		(26 "In12.Cu" signal "GND5")
		(28 "In13.Cu" signal "IN5")
		(30 "In14.Cu" signal "GND6")
		(32 "In15.Cu" signal "IN6")
		(34 "In16.Cu" signal "GND7")
		(2 "B.Cu" signal "BOTTOM")
		(9 "F.Adhes" user "F.Adhesive")
		(11 "B.Adhes" user "B.Adhesive")
		(13 "F.Paste" user "Package Geometry/Pastemask Top")
		(15 "B.Paste" user "Package Geometry/Pastemask Bottom")
		(5 "F.SilkS" user "Ref Des/Silkscreen Top")
		(7 "B.SilkS" user "Ref Des/Silkscreen Bottom")
		(1 "F.Mask" user "Board Geometry/Soldermask Top")
		(3 "B.Mask" user "Board Geometry/Soldermask Bottom")
		(17 "Dwgs.User" user "User.Drawings")
		(19 "Cmts.User" user "User.Comments")
		(21 "Eco1.User" user "User.Eco1")
		(23 "Eco2.User" user "User.Eco2")
		(25 "Edge.Cuts" user "Board Geometry/Outline")
		(27 "Margin" user)
		(31 "F.CrtYd" user "Package Geometry/Place Bound Top")
		(29 "B.CrtYd" user "Package Geometry/Place Bound Bottom")
		(35 "F.Fab" user "Ref Des/Assembly Top")
		(33 "B.Fab" user "Ref Des/Assembly Bottom")
	)
	(footprint ""
		(layer "F.Cu")
		(at 424.204892 -395.619478)
		(property "Reference" "R3437"
			(at 0 0 0)
			(layer "F.SilkS")
			(hide yes)
			(effects
				(font
					(size 1.27 1.27)
				)
			)
		)
		(property "Value" ""
			(at 0 0 0)
			(layer "F.Fab")
			(effects
				(font
					(size 1.27 1.27)
				)
			)
		)
		(duplicate_pad_numbers_are_jumpers no)
		(fp_line
			(start -0.7874 -0.4064)
			(end 0.7874 -0.4064)
			(stroke
				(width 0.1524)
				(type default)
			)
			(layer "F.SilkS")
		)
		(fp_line
			(start -0.7874 0.4064)
			(end -0.7874 -0.4064)
			(stroke
				(width 0.1524)
				(type default)
			)
			(layer "F.SilkS")
		)
		(fp_line
			(start 0.7874 -0.4064)
			(end 0.7874 0.4064)
			(stroke
				(width 0.1524)
				(type default)
			)
			(layer "F.SilkS")
		)
		(fp_line
			(start 0.7874 0.4064)
			(end -0.7874 0.4064)
			(stroke
				(width 0.1524)
				(type default)
			)
			(layer "F.SilkS")
		)
		(fp_line
			(start -0.67945 -0.305054)
			(end -0.12065 -0.305054)
			(stroke
				(width 0.1)
				(type default)
			)
			(layer "F.Fab")
		)
		(fp_line
			(start -0.67945 0.3048)
			(end -0.67945 -0.305054)
			(stroke
				(width 0.1)
				(type default)
			)
			(layer "F.Fab")
		)
		(fp_line
			(start -0.12065 -0.305054)
			(end -0.12065 -0.2794)
			(stroke
				(width 0.1)
				(type default)
			)
			(layer "F.Fab")
		)
		(fp_line
			(start -0.12065 -0.2794)
			(end 0.12065 -0.2794)
			(stroke
				(width 0.1)
				(type default)
			)
			(layer "F.Fab")
		)
		(fp_line
			(start -0.12065 0.2794)
			(end -0.12065 0.3048)
			(stroke
				(width 0.1)
				(type default)
			)
			(layer "F.Fab")
		)
		(fp_line
			(start -0.12065 0.3048)
			(end -0.67945 0.3048)
			(stroke
				(width 0.1)
				(type default)
			)
			(layer "F.Fab")
		)
		(fp_line
			(start 0.120396 0.2794)
			(end -0.12065 0.2794)
			(stroke
				(width 0.1)
				(type default)
			)
			(layer "F.Fab")
		)
		(fp_line
			(start 0.120396 0.3048)
			(end 0.120396 0.2794)
			(stroke
				(width 0.1)
				(type default)
			)
			(layer "F.Fab")
		)
		(fp_line
			(start 0.12065 -0.3048)
			(end 0.67945 -0.3048)
			(stroke
				(width 0.1)
				(type default)
			)
			(layer "F.Fab")
		)
		(fp_line
			(start 0.12065 -0.2794)
			(end 0.12065 -0.3048)
			(stroke
				(width 0.1)
				(type default)
			)
			(layer "F.Fab")
		)
		(fp_line
			(start 0.67945 -0.3048)
			(end 0.67945 0.3048)
			(stroke
				(width 0.1)
				(type default)
			)
			(layer "F.Fab")
		)
		(fp_line
			(start 0.67945 0.3048)
			(end 0.120396 0.3048)
			(stroke
				(width 0.1)
				(type default)
			)
			(layer "F.Fab")
		)
		(pad "1" smd circle
			(at -0.40005 0)
			(size 0 0)
			(layers "F.Cu" "F.Mask" "F.Paste")
			(net "P3V3_AUX")
		)
		(pad "2" smd circle
			(at 0.40005 0)
			(size 0 0)
			(layers "F.Cu" "F.Mask" "F.Paste")
			(net "GPU_FPGA_OVERT_ISO_N")
		)
	)
	(footprint ""
		(layer "F.Cu")
		(at 23.890478 -17.623536 90)
		(property "Reference" "C812"
			(at 0 0 90)
			(layer "F.SilkS")
			(hide yes)
			(effects
				(font
					(size 1.27 1.27)
				)
			)
		)
		(property "Value" ""
			(at 0 0 90)
			(layer "F.Fab")
			(effects
				(font
					(size 1.27 1.27)
				)
			)
		)
		(duplicate_pad_numbers_are_jumpers no)
		(fp_line
			(start 0.299974 -0.150114)
			(end 0.299974 0.150114)
			(stroke
				(width 0.1)
				(type default)
			)
			(layer "F.Fab")
		)
		(fp_line
			(start -0.299974 -0.150114)
			(end 0.299974 -0.150114)
			(stroke
				(width 0.1)
				(type default)
			)
			(layer "F.Fab")
		)
		(fp_line
			(start 0.299974 0.150114)
			(end -0.299974 0.150114)
			(stroke
				(width 0.1)
				(type default)
			)
			(layer "F.Fab")
		)
		(fp_line
			(start -0.299974 0.150114)
			(end -0.299974 -0.150114)
			(stroke
				(width 0.1)
				(type default)
			)
			(layer "F.Fab")
		)
		(pad "1" smd rect
			(at -0.2667 0 90)
			(size 0.3048 0.381)
			(layers "F.Cu" "F.Mask" "F.Paste")
			(net "P5E_CPU1_PE1_TX_C_DN<12>")
		)
		(pad "2" smd rect
			(at 0.2667 0 90)
			(size 0.3048 0.381)
			(layers "F.Cu" "F.Mask" "F.Paste")
			(net "P5E_CPU1_PE1_TX_DN<12>")
		)
	)
	(footprint ""
		(layer "F.Cu")
		(at 356.616 -415.127948)
		(property "Reference" "R4561"
			(at 0 0 0)
			(layer "F.SilkS")
			(hide yes)
			(effects
				(font
					(size 1.27 1.27)
				)
			)
		)
		(property "Value" ""
			(at 0 0 0)
			(layer "F.Fab")
			(effects
				(font
					(size 1.27 1.27)
				)
			)
		)
		(duplicate_pad_numbers_are_jumpers no)
		(fp_line
			(start -0.7874 -0.4064)
			(end 0.7874 -0.4064)
			(stroke
				(width 0.1524)
				(type default)
			)
			(layer "F.SilkS")
		)
		(fp_line
			(start -0.7874 0.4064)
			(end -0.7874 -0.4064)
			(stroke
				(width 0.1524)
				(type default)
			)
			(layer "F.SilkS")
		)
		(fp_line
			(start 0.7874 -0.4064)
			(end 0.7874 0.4064)
			(stroke
				(width 0.1524)
				(type default)
			)
			(layer "F.SilkS")
		)
		(fp_line
			(start 0.7874 0.4064)
			(end -0.7874 0.4064)
			(stroke
				(width 0.1524)
				(type default)
			)
			(layer "F.SilkS")
		)
		(fp_line
			(start -0.67945 -0.305054)
			(end -0.12065 -0.305054)
			(stroke
				(width 0.1)
				(type default)
			)
			(layer "F.Fab")
		)
		(fp_line
			(start -0.67945 0.3048)
			(end -0.67945 -0.305054)
			(stroke
				(width 0.1)
				(type default)
			)
			(layer "F.Fab")
		)
		(fp_line
			(start -0.12065 -0.305054)
			(end -0.12065 -0.2794)
			(stroke
				(width 0.1)
				(type default)
			)
			(layer "F.Fab")
		)
		(fp_line
			(start -0.12065 -0.2794)
			(end 0.12065 -0.2794)
			(stroke
				(width 0.1)
				(type default)
			)
			(layer "F.Fab")
		)
		(fp_line
			(start -0.12065 0.2794)
			(end -0.12065 0.3048)
			(stroke
				(width 0.1)
				(type default)
			)
			(layer "F.Fab")
		)
		(fp_line
			(start -0.12065 0.3048)
			(end -0.67945 0.3048)
			(stroke
				(width 0.1)
				(type default)
			)
			(layer "F.Fab")
		)
		(fp_line
			(start 0.120396 0.2794)
			(end -0.12065 0.2794)
			(stroke
				(width 0.1)
				(type default)
			)
			(layer "F.Fab")
		)
		(fp_line
			(start 0.120396 0.3048)
			(end 0.120396 0.2794)
			(stroke
				(width 0.1)
				(type default)
			)
			(layer "F.Fab")
		)
		(fp_line
			(start 0.12065 -0.3048)
			(end 0.67945 -0.3048)
			(stroke
				(width 0.1)
				(type default)
			)
			(layer "F.Fab")
		)
		(fp_line
			(start 0.12065 -0.2794)
			(end 0.12065 -0.3048)
			(stroke
				(width 0.1)
				(type default)
			)
			(layer "F.Fab")
		)
		(fp_line
			(start 0.67945 -0.3048)
			(end 0.67945 0.3048)
			(stroke
				(width 0.1)
				(type default)
			)
			(layer "F.Fab")
		)
		(fp_line
			(start 0.67945 0.3048)
			(end 0.120396 0.3048)
			(stroke
				(width 0.1)
				(type default)
			)
			(layer "F.Fab")
		)
		(pad "1" smd circle
			(at -0.40005 0)
			(size 0 0)
			(layers "F.Cu" "F.Mask" "F.Paste")
			(net "P3V3_AUX")
		)
		(pad "2" smd circle
			(at 0.40005 0)
			(size 0 0)
			(layers "F.Cu" "F.Mask" "F.Paste")
			(net "SWB_HSC_PWRGD_ISO")
		)
	)
)
